(kicad_pcb
	(version 20260206)
	(generator "pcbnew")
	(generator_version "10.0")
	(general
		(thickness 1.6)
		(legacy_teardrops no)
	)
	(paper "A4")
	(title_block
		(title "peb — Lightning_PEB_BRD.brd")
		(comment 1 "Lightning (Wiwynn / Facebook NVMe JBOF) / footprints 2319-2327 of 2563")
	)
	(layers
		(0 "F.Cu" signal "TOP")
		(4 "In1.Cu" signal "L2GND")
		(6 "In2.Cu" signal "L3")
		(8 "In3.Cu" signal "L4VCC")
		(10 "In4.Cu" signal "L5VCC")
		(12 "In5.Cu" signal "L6")
		(14 "In6.Cu" signal "L7GND")
		(2 "B.Cu" signal "BOTTOM")
		(9 "F.Adhes" user "F.Adhesive")
		(11 "B.Adhes" user "B.Adhesive")
		(13 "F.Paste" user "Package Geometry/Pastemask Top")
		(15 "B.Paste" user "Package Geometry/Pastemask Bottom")
		(5 "F.SilkS" user "Ref Des/Silkscreen Top")
		(7 "B.SilkS" user "Ref Des/Silkscreen Bottom")
		(1 "F.Mask" user "Board Geometry/Soldermask Top")
		(3 "B.Mask" user "Board Geometry/Soldermask Bottom")
		(17 "Dwgs.User" user "User.Drawings")
		(19 "Cmts.User" user "User.Comments")
		(21 "Eco1.User" user "User.Eco1")
		(23 "Eco2.User" user "User.Eco2")
		(25 "Edge.Cuts" user "Board Geometry/Outline")
		(27 "Margin" user)
		(31 "F.CrtYd" user "Package Geometry/Place Bound Top")
		(29 "B.CrtYd" user "Package Geometry/Place Bound Bottom")
		(35 "F.Fab" user "Ref Des/Assembly Top")
		(33 "B.Fab" user "Ref Des/Assembly Bottom")
	)
	(footprint ""
		(layer "B.Cu")
		(at 310.007 -63.119 180)
		(property "Reference" "PG53"
			(at 0 0 0)
			(layer "B.SilkS")
			(hide yes)
			(effects
				(font
					(size 1.27 1.27)
				)
				(justify mirror)
			)
		)
		(property "Value" "GAP-CLOSE-PWR-3-GP"
			(at -0.0254 -6.5786 180)
			(unlocked yes)
			(layer "B.Fab")
			(hide yes)
			(effects
				(font
					(size 1.016 1.016)
					(thickness 0.1524)
				)
				(justify mirror)
			)
		)
		(property "Device Type" "GAP-CLOSE-PWR-3"
			(at -0.0254 -8.255 180)
			(unlocked yes)
			(layer "B.Fab")
			(hide yes)
			(effects
				(font
					(size 1.016 1.016)
					(thickness 0.1524)
				)
				(justify mirror)
			)
		)
		(duplicate_pad_numbers_are_jumpers no)
		(fp_rect
			(start 0.7112 0.4572)
			(end -0.7112 -0.4572)
			(stroke
				(width 0)
				(type default)
			)
			(fill no)
			(layer "B.CrtYd")
		)
		(fp_poly
			(pts
				(xy 0.7112 -0.4572) (xy -0.7112 -0.4572) (xy -0.7112 0.4572) (xy 0.7112 0.4572)
			)
			(stroke
				(width 0)
				(type default)
			)
			(fill no)
			(layer "B.Fab")
		)
		(pad "1" smd rect
			(at 0.3048 0)
			(size 0.6604 0.762)
			(layers "B.Cu" "B.Mask" "B.Paste")
			(net "DUT_VDD")
		)
		(pad "2" smd rect
			(at -0.3048 0)
			(size 0.6604 0.762)
			(layers "B.Cu" "B.Mask" "B.Paste")
			(net "P0V9_E")
		)
	)
	(footprint ""
		(layer "B.Cu")
		(at 273.2532 -1.9304 90)
		(property "Reference" "R2908"
			(at 0 0 90)
			(layer "B.SilkS")
			(hide yes)
			(effects
				(font
					(size 1.27 1.27)
				)
				(justify mirror)
			)
		)
		(property "Value" "0R2J-2-GP"
			(at -0.064008 -3.993896 90)
			(unlocked yes)
			(layer "B.Fab")
			(hide yes)
			(effects
				(font
					(size 1.016 1.016)
					(thickness 0.1524)
				)
				(justify mirror)
			)
		)
		(property "Device Type" "R402H16"
			(at -0.064008 -5.517896 90)
			(unlocked yes)
			(layer "B.Fab")
			(hide yes)
			(effects
				(font
					(size 1.016 1.016)
					(thickness 0.1524)
				)
				(justify mirror)
			)
		)
		(duplicate_pad_numbers_are_jumpers no)
		(fp_line
			(start 0.508 -0.9398)
			(end 0.508 0.9398)
			(stroke
				(width 0.1524)
				(type default)
			)
			(layer "B.SilkS")
		)
		(fp_line
			(start -0.508 -0.9398)
			(end 0.508 -0.9398)
			(stroke
				(width 0.1524)
				(type default)
			)
			(layer "B.SilkS")
		)
		(fp_rect
			(start 0.508 0.9398)
			(end -0.508 -0.9398)
			(stroke
				(width 0)
				(type default)
			)
			(fill no)
			(layer "B.CrtYd")
		)
		(fp_rect
			(start 0.508 0.9398)
			(end -0.508 -0.9398)
			(stroke
				(width 0)
				(type default)
			)
			(fill no)
			(layer "B.Fab")
		)
		(pad "1" smd custom
			(at 0 -0.4445 270)
			(size 0.1397 0.1397)
			(layers "B.Cu" "B.Mask" "B.Paste")
			(net "CBL_PRSNT_N_8")
			(options
				(clearance outline)
				(anchor circle)
			)
			(primitives
				(gr_poly
					(pts
						(arc
							(start -0.1778 0.2794)
							(mid -0.249642 0.249642)
							(end -0.2794 0.1778)
						)
						(arc
							(start -0.2794 -0.1778)
							(mid -0.249642 -0.249642)
							(end -0.1778 -0.2794)
						)
						(arc
							(start 0.1778 -0.2794)
							(mid 0.249642 -0.249642)
							(end 0.2794 -0.1778)
						)
						(arc
							(start 0.2794 0.1778)
							(mid 0.249642 0.249642)
							(end 0.1778 0.2794)
						)
					)
					(width 0)
					(fill yes)
				)
			)
		)
		(pad "2" smd custom
			(at 0 0.4445 270)
			(size 0.1397 0.1397)
			(layers "B.Cu" "B.Mask" "B.Paste")
			(net "8644_CBL_PRSNT_R_8")
			(options
				(clearance outline)
				(anchor circle)
			)
			(primitives
				(gr_poly
					(pts
						(arc
							(start -0.1778 0.2794)
							(mid -0.249642 0.249642)
							(end -0.2794 0.1778)
						)
						(arc
							(start -0.2794 -0.1778)
							(mid -0.249642 -0.249642)
							(end -0.1778 -0.2794)
						)
						(arc
							(start 0.1778 -0.2794)
							(mid 0.249642 -0.249642)
							(end 0.2794 -0.1778)
						)
						(arc
							(start 0.2794 0.1778)
							(mid 0.249642 0.249642)
							(end 0.1778 0.2794)
						)
					)
					(width 0)
					(fill yes)
				)
			)
		)
	)
	(footprint ""
		(layer "B.Cu")
		(at 242.062 -26.543 90)
		(property "Reference" "TP196"
			(at 0 0 90)
			(layer "B.SilkS")
			(hide yes)
			(effects
				(font
					(size 1.27 1.27)
				)
				(justify mirror)
			)
		)
		(property "Value" "TPAD28-2-GP"
			(at 0.0127 -1.6637 90)
			(unlocked yes)
			(layer "B.Fab")
			(hide yes)
			(effects
				(font
					(size 1.016 1.016)
					(thickness 0.1524)
				)
				(justify mirror)
			)
		)
		(property "Device Type" "TPAD28"
			(at 0.0127 -3.1877 90)
			(unlocked yes)
			(layer "B.Fab")
			(hide yes)
			(effects
				(font
					(size 1.016 1.016)
					(thickness 0.1524)
				)
				(justify mirror)
			)
		)
		(duplicate_pad_numbers_are_jumpers no)
		(fp_poly
			(pts
				(arc
					(start 0 0.3556)
					(mid 0 -0.3556)
					(end 0 0.3556)
				)
			)
			(stroke
				(width 0)
				(type default)
			)
			(fill no)
			(layer "B.CrtYd")
		)
		(fp_poly
			(pts
				(arc
					(start 0 0.6096)
					(mid 0 -0.6096)
					(end 0 0.6096)
				)
			)
			(stroke
				(width 0)
				(type default)
			)
			(fill no)
			(layer "B.Fab")
		)
		(pad "1" smd circle
			(at 0 0 270)
			(size 0.7112 0.7112)
			(layers "B.Cu" "B.Mask" "B.Paste")
			(net "LBI_CE#2")
		)
	)
	(footprint ""
		(layer "B.Cu")
		(at 231.5972 -54.991 -90)
		(property "Reference" "C515"
			(at 0 0 90)
			(layer "B.SilkS")
			(hide yes)
			(effects
				(font
					(size 1.27 1.27)
				)
				(justify mirror)
			)
		)
		(property "Value" "SCD1U16V1KX-1-GP"
			(at 2.8321 -1.7399 270)
			(unlocked yes)
			(layer "B.Fab")
			(hide yes)
			(effects
				(font
					(size 1.016 1.016)
					(thickness 0.1524)
				)
				(justify mirror)
			)
		)
		(property "Device Type" "C0201H13"
			(at 2.8321 -3.2639 270)
			(unlocked yes)
			(layer "B.Fab")
			(hide yes)
			(effects
				(font
					(size 1.016 1.016)
					(thickness 0.1524)
				)
				(justify mirror)
			)
		)
		(duplicate_pad_numbers_are_jumpers no)
		(fp_rect
			(start 0.2794 0.6477)
			(end -0.2794 -0.6477)
			(stroke
				(width 0)
				(type default)
			)
			(fill no)
			(layer "B.CrtYd")
		)
		(fp_rect
			(start 0.2794 0.6477)
			(end -0.2794 -0.6477)
			(stroke
				(width 0)
				(type default)
			)
			(fill no)
			(layer "B.Fab")
		)
		(pad "1" smd custom
			(at 0 -0.2794 90)
			(size 0.0762 0.0762)
			(layers "B.Cu" "B.Mask" "B.Paste")
			(net "DUT_AVD_PCIE_Q")
			(options
				(clearance outline)
				(anchor circle)
			)
			(primitives
				(gr_poly
					(pts
						(arc
							(start 0.1524 0.127)
							(mid 0.137521 0.162921)
							(end 0.1016 0.1778)
						)
						(arc
							(start -0.1016 0.1778)
							(mid -0.137521 0.162921)
							(end -0.1524 0.127)
						)
						(arc
							(start -0.1524 -0.127)
							(mid -0.137521 -0.162921)
							(end -0.1016 -0.1778)
						)
						(arc
							(start 0.1016 -0.1778)
							(mid 0.137521 -0.162921)
							(end 0.1524 -0.127)
						)
					)
					(width 0)
					(fill yes)
				)
			)
		)
		(pad "2" smd custom
			(at 0 0.2794 90)
			(size 0.0762 0.0762)
			(layers "B.Cu" "B.Mask" "B.Paste")
			(net "GND")
			(options
				(clearance outline)
				(anchor circle)
			)
			(primitives
				(gr_poly
					(pts
						(arc
							(start 0.1524 0.127)
							(mid 0.137521 0.162921)
							(end 0.1016 0.1778)
						)
						(arc
							(start -0.1016 0.1778)
							(mid -0.137521 0.162921)
							(end -0.1524 0.127)
						)
						(arc
							(start -0.1524 -0.127)
							(mid -0.137521 -0.162921)
							(end -0.1016 -0.1778)
						)
						(arc
							(start 0.1016 -0.1778)
							(mid 0.137521 -0.162921)
							(end 0.1524 -0.127)
						)
					)
					(width 0)
					(fill yes)
				)
			)
		)
	)
	(footprint ""
		(layer "B.Cu")
		(at 237.109 -20.447)
		(property "Reference" "R815"
			(at 0 0 0)
			(layer "B.SilkS")
			(hide yes)
			(effects
				(font
					(size 1.27 1.27)
				)
				(justify mirror)
			)
		)
		(property "Value" "4K7R2F-GP"
			(at -0.064008 -3.993896 0)
			(unlocked yes)
			(layer "B.Fab")
			(hide yes)
			(effects
				(font
					(size 1.016 1.016)
					(thickness 0.1524)
				)
				(justify mirror)
			)
		)
		(property "Device Type" "R402H16"
			(at -0.064008 -5.517896 0)
			(unlocked yes)
			(layer "B.Fab")
			(hide yes)
			(effects
				(font
					(size 1.016 1.016)
					(thickness 0.1524)
				)
				(justify mirror)
			)
		)
		(duplicate_pad_numbers_are_jumpers no)
		(fp_line
			(start -0.508 -0.9398)
			(end 0.508 -0.9398)
			(stroke
				(width 0.1524)
				(type default)
			)
			(layer "B.SilkS")
		)
		(fp_line
			(start 0.508 -0.9398)
			(end 0.508 0.9398)
			(stroke
				(width 0.1524)
				(type default)
			)
			(layer "B.SilkS")
		)
		(fp_rect
			(start 0.508 0.9398)
			(end -0.508 -0.9398)
			(stroke
				(width 0)
				(type default)
			)
			(fill no)
			(layer "B.CrtYd")
		)
		(fp_rect
			(start 0.508 0.9398)
			(end -0.508 -0.9398)
			(stroke
				(width 0)
				(type default)
			)
			(fill no)
			(layer "B.Fab")
		)
		(pad "1" smd custom
			(at 0 -0.4445 180)
			(size 0.1397 0.1397)
			(layers "B.Cu" "B.Mask" "B.Paste")
			(net "BOOTSTRAP7")
			(options
				(clearance outline)
				(anchor circle)
			)
			(primitives
				(gr_poly
					(pts
						(arc
							(start -0.1778 0.2794)
							(mid -0.249642 0.249642)
							(end -0.2794 0.1778)
						)
						(arc
							(start -0.2794 -0.1778)
							(mid -0.249642 -0.249642)
							(end -0.1778 -0.2794)
						)
						(arc
							(start 0.1778 -0.2794)
							(mid 0.249642 -0.249642)
							(end 0.2794 -0.1778)
						)
						(arc
							(start 0.2794 0.1778)
							(mid 0.249642 0.249642)
							(end 0.1778 0.2794)
						)
					)
					(width 0)
					(fill yes)
				)
			)
		)
		(pad "2" smd custom
			(at 0 0.4445 180)
			(size 0.1397 0.1397)
			(layers "B.Cu" "B.Mask" "B.Paste")
			(net "DUT_VDDO")
			(options
				(clearance outline)
				(anchor circle)
			)
			(primitives
				(gr_poly
					(pts
						(arc
							(start -0.1778 0.2794)
							(mid -0.249642 0.249642)
							(end -0.2794 0.1778)
						)
						(arc
							(start -0.2794 -0.1778)
							(mid -0.249642 -0.249642)
							(end -0.1778 -0.2794)
						)
						(arc
							(start 0.1778 -0.2794)
							(mid 0.249642 -0.249642)
							(end 0.2794 -0.1778)
						)
						(arc
							(start 0.2794 0.1778)
							(mid 0.249642 0.249642)
							(end 0.1778 0.2794)
						)
					)
					(width 0)
					(fill yes)
				)
			)
		)
	)
	(footprint ""
		(layer "B.Cu")
		(at 242.599972 -37.999924)
		(property "Reference" "TP265"
			(at 0 0 0)
			(layer "B.SilkS")
			(hide yes)
			(effects
				(font
					(size 1.27 1.27)
				)
				(justify mirror)
			)
		)
		(property "Value" "TPAD28-2-GP"
			(at 0.0127 -1.6637 0)
			(unlocked yes)
			(layer "B.Fab")
			(hide yes)
			(effects
				(font
					(size 1.016 1.016)
					(thickness 0.1524)
				)
				(justify mirror)
			)
		)
		(property "Device Type" "TPAD28"
			(at 0.0127 -3.1877 0)
			(unlocked yes)
			(layer "B.Fab")
			(hide yes)
			(effects
				(font
					(size 1.016 1.016)
					(thickness 0.1524)
				)
				(justify mirror)
			)
		)
		(duplicate_pad_numbers_are_jumpers no)
		(fp_poly
			(pts
				(arc
					(start 0.3556 0)
					(mid -0.3556 0)
					(end 0.3556 0)
				)
			)
			(stroke
				(width 0)
				(type default)
			)
			(fill no)
			(layer "B.CrtYd")
		)
		(fp_poly
			(pts
				(arc
					(start 0.6096 0)
					(mid -0.6096 0)
					(end 0.6096 0)
				)
			)
			(stroke
				(width 0)
				(type default)
			)
			(fill no)
			(layer "B.Fab")
		)
		(pad "1" smd circle
			(at 0 0 180)
			(size 0.7112 0.7112)
			(layers "B.Cu" "B.Mask" "B.Paste")
			(net "LBI_DATA_6")
		)
	)
	(footprint ""
		(layer "B.Cu")
		(at 43.942 -139.065)
		(property "Reference" "TP321"
			(at 0 0 0)
			(layer "B.SilkS")
			(hide yes)
			(effects
				(font
					(size 1.27 1.27)
				)
				(justify mirror)
			)
		)
		(property "Value" "TPAD28-2-GP"
			(at 0.0127 -1.6637 0)
			(unlocked yes)
			(layer "B.Fab")
			(hide yes)
			(effects
				(font
					(size 1.016 1.016)
					(thickness 0.1524)
				)
				(justify mirror)
			)
		)
		(property "Device Type" "TPAD28"
			(at 0.0127 -3.1877 0)
			(unlocked yes)
			(layer "B.Fab")
			(hide yes)
			(effects
				(font
					(size 1.016 1.016)
					(thickness 0.1524)
				)
				(justify mirror)
			)
		)
		(duplicate_pad_numbers_are_jumpers no)
		(fp_poly
			(pts
				(arc
					(start 0.3556 0)
					(mid -0.3556 0)
					(end 0.3556 0)
				)
			)
			(stroke
				(width 0)
				(type default)
			)
			(fill no)
			(layer "B.CrtYd")
		)
		(fp_poly
			(pts
				(arc
					(start 0.6096 0)
					(mid -0.6096 0)
					(end 0.6096 0)
				)
			)
			(stroke
				(width 0)
				(type default)
			)
			(fill no)
			(layer "B.Fab")
		)
		(pad "1" smd circle
			(at 0 0 180)
			(size 0.7112 0.7112)
			(layers "B.Cu" "B.Mask" "B.Paste")
			(net "TP_GPIOO4")
		)
	)
	(footprint ""
		(layer "B.Cu")
		(at 82.722212 -192.641474)
		(property "Reference" "R3231"
			(at 0 0 0)
			(layer "B.SilkS")
			(hide yes)
			(effects
				(font
					(size 1.27 1.27)
				)
				(justify mirror)
			)
		)
		(property "Value" "0R2J-2-GP"
			(at -0.064008 -3.993896 0)
			(unlocked yes)
			(layer "B.Fab")
			(hide yes)
			(effects
				(font
					(size 1.016 1.016)
					(thickness 0.1524)
				)
				(justify mirror)
			)
		)
		(property "Device Type" "R402H16"
			(at -0.064008 -5.517896 0)
			(unlocked yes)
			(layer "B.Fab")
			(hide yes)
			(effects
				(font
					(size 1.016 1.016)
					(thickness 0.1524)
				)
				(justify mirror)
			)
		)
		(duplicate_pad_numbers_are_jumpers no)
		(fp_line
			(start -0.508 -0.9398)
			(end 0.508 -0.9398)
			(stroke
				(width 0.1524)
				(type default)
			)
			(layer "B.SilkS")
		)
		(fp_line
			(start 0.508 -0.9398)
			(end 0.508 0.9398)
			(stroke
				(width 0.1524)
				(type default)
			)
			(layer "B.SilkS")
		)
		(fp_rect
			(start 0.508 0.9398)
			(end -0.508 -0.9398)
			(stroke
				(width 0)
				(type default)
			)
			(fill no)
			(layer "B.CrtYd")
		)
		(fp_rect
			(start 0.508 0.9398)
			(end -0.508 -0.9398)
			(stroke
				(width 0)
				(type default)
			)
			(fill no)
			(layer "B.Fab")
		)
		(pad "1" smd custom
			(at 0 -0.4445 180)
			(size 0.1397 0.1397)
			(layers "B.Cu" "B.Mask" "B.Paste")
			(net "SSD_PERST#10")
			(options
				(clearance outline)
				(anchor circle)
			)
			(primitives
				(gr_poly
					(pts
						(arc
							(start -0.1778 0.2794)
							(mid -0.249642 0.249642)
							(end -0.2794 0.1778)
						)
						(arc
							(start -0.2794 -0.1778)
							(mid -0.249642 -0.249642)
							(end -0.1778 -0.2794)
						)
						(arc
							(start 0.1778 -0.2794)
							(mid 0.249642 -0.249642)
							(end 0.2794 -0.1778)
						)
						(arc
							(start 0.2794 0.1778)
							(mid 0.249642 0.249642)
							(end 0.1778 0.2794)
						)
					)
					(width 0)
					(fill yes)
				)
			)
		)
		(pad "2" smd custom
			(at 0 0.4445 180)
			(size 0.1397 0.1397)
			(layers "B.Cu" "B.Mask" "B.Paste")
			(net "SSD_PERST#0_B10")
			(options
				(clearance outline)
				(anchor circle)
			)
			(primitives
				(gr_poly
					(pts
						(arc
							(start -0.1778 0.2794)
							(mid -0.249642 0.249642)
							(end -0.2794 0.1778)
						)
						(arc
							(start -0.2794 -0.1778)
							(mid -0.249642 -0.249642)
							(end -0.1778 -0.2794)
						)
						(arc
							(start 0.1778 -0.2794)
							(mid 0.249642 -0.249642)
							(end 0.2794 -0.1778)
						)
						(arc
							(start 0.2794 0.1778)
							(mid 0.249642 0.249642)
							(end 0.1778 0.2794)
						)
					)
					(width 0)
					(fill yes)
				)
			)
		)
	)
	(footprint ""
		(layer "B.Cu")
		(at 177.292 -207.5942 90)
		(property "Reference" "C4148"
			(at 0 0 90)
			(layer "B.SilkS")
			(hide yes)
			(effects
				(font
					(size 1.27 1.27)
				)
				(justify mirror)
			)
		)
		(property "Value" "SCD1U25V3KX-GP"
			(at 0 -2.8194 90)
			(unlocked yes)
			(layer "B.Fab")
			(hide yes)
			(effects
				(font
					(size 1.016 1.016)
					(thickness 0.1524)
				)
				(justify mirror)
			)
		)
		(property "Device Type" "C603H36"
			(at 0 -4.3434 90)
			(unlocked yes)
			(layer "B.Fab")
			(hide yes)
			(effects
				(font
					(size 1.016 1.016)
					(thickness 0.1524)
				)
				(justify mirror)
			)
		)
		(duplicate_pad_numbers_are_jumpers no)
		(fp_line
			(start -0.508 0)
			(end 0.508 0)
			(stroke
				(width 0.2032)
				(type default)
			)
			(layer "B.SilkS")
		)
		(fp_rect
			(start 0.5842 1.3335)
			(end -0.5842 -1.3335)
			(stroke
				(width 0)
				(type default)
			)
			(fill no)
			(layer "B.CrtYd")
		)
		(fp_rect
			(start 0.5842 1.3335)
			(end -0.5842 -1.3335)
			(stroke
				(width 0)
				(type default)
			)
			(fill no)
			(layer "B.Fab")
		)
		(pad "1" smd custom
			(at 0 -0.762 270)
			(size 0.2159 0.2159)
			(layers "B.Cu" "B.Mask" "B.Paste")
			(net "GND")
			(options
				(clearance outline)
				(anchor circle)
			)
			(primitives
				(gr_poly
					(pts
						(arc
							(start -0.3302 0.4318)
							(mid -0.402042 0.402042)
							(end -0.4318 0.3302)
						)
						(arc
							(start -0.4318 -0.3302)
							(mid -0.402042 -0.402042)
							(end -0.3302 -0.4318)
						)
						(arc
							(start 0.3302 -0.4318)
							(mid 0.402042 -0.402042)
							(end 0.4318 -0.3302)
						)
						(arc
							(start 0.4318 0.3302)
							(mid 0.402042 0.402042)
							(end 0.3302 0.4318)
						)
					)
					(width 0)
					(fill yes)
				)
			)
		)
		(pad "2" smd custom
			(at 0 0.762 270)
			(size 0.2159 0.2159)
			(layers "B.Cu" "B.Mask" "B.Paste")
			(net "SSD_PWREN7_R")
			(options
				(clearance outline)
				(anchor circle)
			)
			(primitives
				(gr_poly
					(pts
						(arc
							(start -0.3302 0.4318)
							(mid -0.402042 0.402042)
							(end -0.4318 0.3302)
						)
						(arc
							(start -0.4318 -0.3302)
							(mid -0.402042 -0.402042)
							(end -0.3302 -0.4318)
						)
						(arc
							(start 0.3302 -0.4318)
							(mid 0.402042 -0.402042)
							(end 0.4318 -0.3302)
						)
						(arc
							(start 0.4318 0.3302)
							(mid 0.402042 0.402042)
							(end 0.3302 0.4318)
						)
					)
					(width 0)
					(fill yes)
				)
			)
		)
	)
)
